(kicad_pcb
	(version 20241229)
	(generator "pcbnew")
	(generator_version "9.0")
	(general
		(thickness 1.6)
		(legacy_teardrops no)
	)
	(paper "A4")
	(title_block
		(title "GMSL Deserializer")
		(date "2025-10-09")
		(rev "1.0.4")
		(company "Antmicro Ltd")
		(comment 1 "www.antmicro.com")
		(comment 9 "footprints 134-138 of 235")
	)
	(layers
		(0 "F.Cu" signal)
		(4 "In1.Cu" power)
		(6 "In2.Cu" power)
		(2 "B.Cu" signal)
		(9 "F.Adhes" user "F.Adhesive")
		(11 "B.Adhes" user "B.Adhesive")
		(13 "F.Paste" user)
		(15 "B.Paste" user)
		(5 "F.SilkS" user "F.Silkscreen")
		(7 "B.SilkS" user "B.Silkscreen")
		(1 "F.Mask" user)
		(3 "B.Mask" user)
		(17 "Dwgs.User" user "User.Drawings")
		(19 "Cmts.User" user "User.Comments")
		(21 "Eco1.User" user "User.Eco1")
		(23 "Eco2.User" user "User.Eco2")
		(25 "Edge.Cuts" user)
		(27 "Margin" user)
		(31 "F.CrtYd" user "F.Courtyard")
		(29 "B.CrtYd" user "B.Courtyard")
		(35 "F.Fab" user)
		(33 "B.Fab" user)
	)
	(footprint "antmicro-footprints:C_0402_1005Metric"
		(layer "F.Cu")
		(at 152.654 76.2 45)
		(descr "Capacitor SMD 0402")
		(tags "capacitor SMD 0402")
		(property "Reference" "C35"
			(at 4.003639 0.193747 45)
			(layer "F.SilkS")
			(effects
				(font
					(size 0.7 0.7)
					(thickness 0.15)
				)
				(justify left bottom)
			)
		)
		(property "Value" "C_100n_0402"
			(at -1.022927 2.155213 45)
			(layer "F.Fab")
			(effects
				(font
					(size 0.7 0.7)
					(thickness 0.15)
				)
				(justify left bottom)
			)
		)
		(property "Datasheet" "https://www.murata.com/products/productdetail?partno=GRM155R61H104KE14%23"
			(at 0 0 45)
			(layer "F.Fab")
			(hide yes)
			(effects
				(font
					(size 1.27 1.27)
					(thickness 0.15)
				)
			)
		)
		(property "Description" "SMD Multilayer Ceramic Capacitor, 0.1 µF, 50 V, 0402 [1005 Metric], ± 10%, X5R, GRM Series"
			(at 0 0 45)
			(layer "F.Fab")
			(hide yes)
			(effects
				(font
					(size 1.27 1.27)
					(thickness 0.15)
				)
			)
		)
		(property "Author" "Antmicro"
			(at 98.592858 -85.624216 0)
			(layer "F.Fab")
			(hide yes)
			(effects
				(font
					(size 1 1)
					(thickness 0.15)
				)
			)
		)
		(property "Dielectric" "X5R"
			(at 98.592858 -85.624216 0)
			(layer "F.Fab")
			(hide yes)
			(effects
				(font
					(size 1 1)
					(thickness 0.15)
				)
			)
		)
		(property "License" "Apache-2.0"
			(at 98.592858 -85.624216 0)
			(layer "F.Fab")
			(hide yes)
			(effects
				(font
					(size 1 1)
					(thickness 0.15)
				)
			)
		)
		(property "MPN" "GRM155R61H104KE14D"
			(at 98.592858 -85.624216 0)
			(layer "F.Fab")
			(hide yes)
			(effects
				(font
					(size 1 1)
					(thickness 0.15)
				)
			)
		)
		(property "Manufacturer" "Murata"
			(at 98.592858 -85.624216 0)
			(layer "F.Fab")
			(hide yes)
			(effects
				(font
					(size 1 1)
					(thickness 0.15)
				)
			)
		)
		(property "Val" "100n"
			(at 98.592858 -85.624216 0)
			(layer "F.Fab")
			(hide yes)
			(effects
				(font
					(size 1 1)
					(thickness 0.15)
				)
			)
		)
		(property "Voltage" "50V"
			(at 98.592858 -85.624216 0)
			(layer "F.Fab")
			(hide yes)
			(effects
				(font
					(size 1 1)
					(thickness 0.15)
				)
			)
		)
		(sheetname "/Deserializer/")
		(sheetfile "deserializer.kicad_sch")
		(attr smd)
		(fp_poly
			(pts
				(xy -0.925 -0.47) (xy 0.925 -0.47) (xy 0.925 0.47) (xy -0.925 0.47)
			)
			(stroke
				(width 0.05)
				(type default)
			)
			(fill no)
			(layer "F.CrtYd")
		)
		(fp_line
			(start -0.494 -0.25)
			(end 0.504 -0.25)
			(stroke
				(width 0.15)
				(type solid)
			)
			(layer "F.Fab")
		)
		(fp_line
			(start -0.494 0.248)
			(end -0.494 -0.25)
			(stroke
				(width 0.15)
				(type solid)
			)
			(layer "F.Fab")
		)
		(fp_line
			(start 0.504 -0.25)
			(end 0.504 0.248)
			(stroke
				(width 0.15)
				(type solid)
			)
			(layer "F.Fab")
		)
		(fp_line
			(start 0.504 0.248)
			(end -0.494 0.248)
			(stroke
				(width 0.15)
				(type solid)
			)
			(layer "F.Fab")
		)
		(pad "1" smd roundrect
			(at -0.48 0 45)
			(size 0.59 0.64)
			(layers "F.Cu" "F.Mask" "F.Paste")
			(roundrect_rratio 0.25)
			(net 24 "/Deserializer/SIOD_N")
			(pintype "passive")
		)
		(pad "2" smd roundrect
			(at 0.48 0 45)
			(size 0.59 0.64)
			(layers "F.Cu" "F.Mask" "F.Paste")
			(roundrect_rratio 0.25)
			(net 25 "Net-(C35-Pad2)")
			(pintype "passive")
		)
	)
	(footprint "antmicro-footprints:R_0402_1005Metric"
		(layer "F.Cu")
		(at 168.91 64.135 90)
		(descr "Resistor SMD 0402")
		(tags "resistor SMD 0402")
		(property "Reference" "R3"
			(at -2.248717 0.4705 90)
			(layer "F.SilkS")
			(effects
				(font
					(size 0.7 0.7)
					(thickness 0.15)
				)
				(justify left bottom)
			)
		)
		(property "Value" "R_0R_0402"
			(at -1.011843 1.772047 90)
			(layer "F.Fab")
			(effects
				(font
					(size 0.7 0.7)
					(thickness 0.15)
				)
				(justify left bottom)
			)
		)
		(property "Datasheet" "https://industrial.panasonic.com/cdbs/www-data/pdf/RDA0000/AOA0000C301.pdf"
			(at 0 0 90)
			(layer "F.Fab")
			(hide yes)
			(effects
				(font
					(size 1.27 1.27)
					(thickness 0.15)
				)
			)
		)
		(property "Description" "SMD Chip Resistor, Jumper, 0 ohm, 100 mW, 0402 [1005 Metric], Thick Film, General Purpose"
			(at 0 0 90)
			(layer "F.Fab")
			(hide yes)
			(effects
				(font
					(size 1.27 1.27)
					(thickness 0.15)
				)
			)
		)
		(property "Author" "Antmicro"
			(at 233.045 -104.775 0)
			(layer "F.Fab")
			(hide yes)
			(effects
				(font
					(size 1 1)
					(thickness 0.15)
				)
			)
		)
		(property "Current" "1A"
			(at 233.045 -104.775 0)
			(layer "F.Fab")
			(hide yes)
			(effects
				(font
					(size 1 1)
					(thickness 0.15)
				)
			)
		)
		(property "License" "Apache-2.0"
			(at 233.045 -104.775 0)
			(layer "F.Fab")
			(hide yes)
			(effects
				(font
					(size 1 1)
					(thickness 0.15)
				)
			)
		)
		(property "MPN" "ERJ2GE0R00X"
			(at 233.045 -104.775 0)
			(layer "F.Fab")
			(hide yes)
			(effects
				(font
					(size 1 1)
					(thickness 0.15)
				)
			)
		)
		(property "Manufacturer" "Panasonic"
			(at 233.045 -104.775 0)
			(layer "F.Fab")
			(hide yes)
			(effects
				(font
					(size 1 1)
					(thickness 0.15)
				)
			)
		)
		(property "Tolerance" ""
			(at 233.045 -104.775 0)
			(layer "F.Fab")
			(hide yes)
			(effects
				(font
					(size 1 1)
					(thickness 0.15)
				)
			)
		)
		(property "Val" "0R"
			(at 233.045 -104.775 0)
			(layer "F.Fab")
			(hide yes)
			(effects
				(font
					(size 1 1)
					(thickness 0.15)
				)
			)
		)
		(sheetname "/Connectors/")
		(sheetfile "connectors.kicad_sch")
		(attr smd)
		(fp_rect
			(start -0.925 -0.47)
			(end 0.925 0.47)
			(stroke
				(width 0.05)
				(type default)
			)
			(fill no)
			(layer "F.CrtYd")
		)
		(fp_rect
			(start -0.5 -0.25)
			(end 0.5 0.25)
			(stroke
				(width 0.15)
				(type solid)
			)
			(fill no)
			(layer "F.Fab")
		)
		(pad "1" smd roundrect
			(at -0.48 0 90)
			(size 0.59 0.64)
			(layers "F.Cu" "F.Mask" "F.Paste")
			(roundrect_rratio 0.25)
			(net 81 "/Connectors/MFP1")
			(pintype "passive")
		)
		(pad "2" smd roundrect
			(at 0.48 0 90)
			(size 0.59 0.64)
			(layers "F.Cu" "F.Mask" "F.Paste")
			(roundrect_rratio 0.25)
			(net 130 "Net-(U1-Y)")
			(pintype "passive")
		)
	)
	(footprint "antmicro-footprints:Conn_FAKRA_7-2287906-0"
		(layer "F.Cu")
		(at 152.283332 38.348)
		(descr "Connector FAKRA, 5 pins")
		(property "Reference" "J4"
			(at 5.054 5.3 0)
			(layer "F.SilkS")
			(effects
				(font
					(size 0.7 0.7)
					(thickness 0.15)
				)
				(justify left bottom)
			)
		)
		(property "Value" "Conn_FAKRA_59S2AQ-40MT5-Z_1"
			(at -6.55 15.019 0)
			(layer "F.Fab")
			(effects
				(font
					(size 0.7 0.7)
					(thickness 0.15)
				)
				(justify left bottom)
			)
		)
		(property ki_fp_filters "*BNC* *SMA* *SMB* *SMC* *Cinch*")
		(sheetname "/Connectors/")
		(sheetfile "connectors.kicad_sch")
		(attr through_hole)
		(fp_line
			(start -4.572 0.94)
			(end -4.572 13.919)
			(stroke
				(width 0.15)
				(type solid)
			)
			(layer "F.SilkS")
		)
		(fp_line
			(start -4.572 13.919)
			(end 4.572 13.919)
			(stroke
				(width 0.15)
				(type solid)
			)
			(layer "F.SilkS")
		)
		(fp_line
			(start 4.572 0.94)
			(end -4.572 0.94)
			(stroke
				(width 0.15)
				(type solid)
			)
			(layer "F.SilkS")
		)
		(fp_line
			(start 4.572 13.919)
			(end 4.572 0.94)
			(stroke
				(width 0.15)
				(type solid)
			)
			(layer "F.SilkS")
		)
		(fp_rect
			(start -5.14 -12.64)
			(end 5.131 14.164)
			(stroke
				(width 0.05)
				(type solid)
			)
			(fill no)
			(layer "F.CrtYd")
		)
		(fp_text user "${REFERENCE}"
			(at -6.55 18.619 0)
			(layer "F.Fab")
			(effects
				(font
					(size 0.7 0.7)
					(thickness 0.15)
				)
				(justify left bottom)
			)
		)
		(fp_text user "Author: Antmicro"
			(at -6.55 17.419 0)
			(layer "F.Fab")
			(effects
				(font
					(size 0.7 0.7)
					(thickness 0.15)
				)
				(justify left bottom)
			)
		)
		(fp_text user "License: Apache-2.0"
			(at -6.55 16.219 0)
			(layer "F.Fab")
			(effects
				(font
					(size 0.7 0.7)
					(thickness 0.15)
				)
				(justify left bottom)
			)
		)
		(pad "1" smd roundrect
			(at 0 3.62 270)
			(size 4.79 1.9)
			(layers "F.Cu" "F.Mask" "F.Paste")
			(roundrect_rratio 0.25)
			(net 116 "/Connectors/PoCC")
			(pinfunction "1")
			(pintype "passive")
		)
		(pad "2" thru_hole circle
			(at -3 3.315 270)
			(size 1.8 1.8)
			(drill 1.45)
			(layers "*.Cu" "*.Mask")
			(remove_unused_layers no)
			(net 1 "GND")
			(pinfunction "2")
			(pintype "passive")
		)
		(pad "2" smd roundrect
			(at -2.9975 3.7175 270)
			(size 4.985 1.8)
			(layers "F.Cu" "F.Mask" "F.Paste")
			(roundrect_rratio 0.25)
			(net 1 "GND")
			(pinfunction "2")
			(pintype "passive")
		)
		(pad "3" thru_hole circle
			(at -3 10.315 270)
			(size 1.8 1.8)
			(drill 1.45)
			(layers "*.Cu" "*.Mask")
			(remove_unused_layers no)
			(net 1 "GND")
			(pinfunction "3")
			(pintype "passive")
		)
		(pad "3" smd roundrect
			(at -3 10.815 270)
			(size 5.6 1.8)
			(layers "F.Cu" "F.Mask" "F.Paste")
			(roundrect_rratio 0.25)
			(net 1 "GND")
			(pinfunction "3")
			(pintype "passive")
		)
		(pad "4" thru_hole circle
			(at 3 10.315 270)
			(size 1.8 1.8)
			(drill 1.45)
			(layers "*.Cu" "*.Mask")
			(remove_unused_layers no)
			(net 1 "GND")
			(pinfunction "4")
			(pintype "passive")
		)
		(pad "4" smd roundrect
			(at 3 10.815 270)
			(size 5.6 1.8)
			(layers "F.Cu" "F.Mask" "F.Paste")
			(roundrect_rratio 0.25)
			(net 1 "GND")
			(pinfunction "4")
			(pintype "passive")
		)
		(pad "5" thru_hole circle
			(at 3 3.315 270)
			(size 1.8 1.8)
			(drill 1.45)
			(layers "*.Cu" "*.Mask")
			(remove_unused_layers no)
			(net 1 "GND")
			(pinfunction "5")
			(pintype "passive")
		)
		(pad "5" smd roundrect
			(at 3 3.72 270)
			(size 4.99 1.8)
			(layers "F.Cu" "F.Mask" "F.Paste")
			(roundrect_rratio 0.25)
			(net 1 "GND")
			(pinfunction "5")
			(pintype "passive")
		)
	)
	(footprint "antmicro-footprints:F_1206_3216Metric"
		(layer "F.Cu")
		(at 171.45 53.34 -90)
		(property "Reference" "F1"
			(at -1.184797 1.152333 90)
			(layer "F.SilkS")
			(effects
				(font
					(size 0.7 0.7)
					(thickness 0.15)
				)
				(justify right bottom)
			)
		)
		(property "Value" "F_4A_1206"
			(at 0 2 90)
			(layer "F.Fab")
			(effects
				(font
					(size 0.7 0.7)
					(thickness 0.15)
				)
				(justify right bottom)
			)
		)
		(property "Datasheet" "https://www.littelfuse.com/media?resourcetype=datasheets&itemid=dbe9bcd7-6072-4adf-bf5b-d33e52a6b90f&filename=littelfuse-fuse-466-datasheet"
			(at 0 0 270)
			(layer "F.Fab")
			(hide yes)
			(effects
				(font
					(size 1.27 1.27)
					(thickness 0.15)
				)
			)
		)
		(property "Description" "Fuse, Surface Mount, 4 A, Very Fast Acting, 32 V, 32 V, 1206 (3216 Metric), 466"
			(at 0 0 270)
			(layer "F.Fab")
			(hide yes)
			(effects
				(font
					(size 1.27 1.27)
					(thickness 0.15)
				)
			)
		)
		(property "Author" "Antmicro"
			(at 118.11 224.79 0)
			(layer "F.Fab")
			(hide yes)
			(effects
				(font
					(size 1 1)
					(thickness 0.15)
				)
			)
		)
		(property "License" "Apache-2.0"
			(at 118.11 224.79 0)
			(layer "F.Fab")
			(hide yes)
			(effects
				(font
					(size 1 1)
					(thickness 0.15)
				)
			)
		)
		(property "MPN" "0466004.NR "
			(at 118.11 224.79 0)
			(layer "F.Fab")
			(hide yes)
			(effects
				(font
					(size 1 1)
					(thickness 0.15)
				)
			)
		)
		(property "Manufacturer" "Littelfuse"
			(at 118.11 224.79 0)
			(layer "F.Fab")
			(hide yes)
			(effects
				(font
					(size 1 1)
					(thickness 0.15)
				)
			)
		)
		(sheetname "/Connectors/")
		(sheetfile "connectors.kicad_sch")
		(attr smd)
		(fp_line
			(start 0.8 0.901)
			(end -0.8 0.901)
			(stroke
				(width 0.15)
				(type solid)
			)
			(layer "F.SilkS")
		)
		(fp_line
			(start 0.8 -0.899)
			(end -0.8 -0.899)
			(stroke
				(width 0.15)
				(type solid)
			)
			(layer "F.SilkS")
		)
		(fp_rect
			(start -2.325 -1.15)
			(end 2.325 1.15)
			(stroke
				(width 0.05)
				(type default)
			)
			(fill no)
			(layer "F.CrtYd")
		)
		(fp_line
			(start -1.677 0.792)
			(end -1.677 -0.861)
			(stroke
				(width 0.15)
				(type solid)
			)
			(layer "F.Fab")
		)
		(fp_line
			(start 1.624 0.792)
			(end -1.677 0.792)
			(stroke
				(width 0.15)
				(type solid)
			)
			(layer "F.Fab")
		)
		(fp_line
			(start -1.677 -0.861)
			(end 1.624 -0.861)
			(stroke
				(width 0.15)
				(type solid)
			)
			(layer "F.Fab")
		)
		(fp_line
			(start 1.624 -0.861)
			(end 1.624 0.792)
			(stroke
				(width 0.15)
				(type solid)
			)
			(layer "F.Fab")
		)
		(pad "1" smd roundrect
			(at -1.5 0.001 270)
			(size 1.15 1.8)
			(layers "F.Cu" "F.Mask" "F.Paste")
			(roundrect_rratio 0.25)
			(net 2 "/Connectors/DC_UNFUSED")
			(pintype "passive")
		)
		(pad "2" smd roundrect
			(at 1.5 0.001 270)
			(size 1.15 1.8)
			(layers "F.Cu" "F.Mask" "F.Paste")
			(roundrect_rratio 0.25)
			(net 118 "/Connectors/DC_IN")
			(pintype "passive")
		)
	)
	(footprint "antmicro-footprints:C_0402_1005Metric"
		(layer "F.Cu")
		(at 126.42 85.702 -90)
		(descr "Capacitor SMD 0402")
		(tags "capacitor SMD 0402")
		(property "Reference" "C22"
			(at -0.485 -2.231 90)
			(layer "F.SilkS")
			(effects
				(font
					(size 0.7 0.7)
					(thickness 0.15)
				)
				(justify right bottom)
			)
		)
		(property "Value" "C_22u_0402"
			(at -1.022927 2.155213 90)
			(layer "F.Fab")
			(effects
				(font
					(size 0.7 0.7)
					(thickness 0.15)
				)
				(justify right bottom)
			)
		)
		(property "Datasheet" "https://www.murata.com/products/productdetail?partno=GRM158R60J226ME01%23"
			(at 0 0 270)
			(layer "F.Fab")
			(hide yes)
			(effects
				(font
					(size 1.27 1.27)
					(thickness 0.15)
				)
			)
		)
		(property "Description" "SMD Multilayer Ceramic Capacitor, 22 uF, 4 V, 0402 [1005 Metric], X6S"
			(at 0 0 270)
			(layer "F.Fab")
			(hide yes)
			(effects
				(font
					(size 1.27 1.27)
					(thickness 0.15)
				)
			)
		)
		(property "Author" "Antmicro"
			(at 40.718 212.122 0)
			(layer "F.Fab")
			(hide yes)
			(effects
				(font
					(size 1 1)
					(thickness 0.15)
				)
			)
		)
		(property "Dielectric" ""
			(at 40.718 212.122 0)
			(layer "F.Fab")
			(hide yes)
			(effects
				(font
					(size 1 1)
					(thickness 0.15)
				)
			)
		)
		(property "License" "Apache-2.0"
			(at 40.718 212.122 0)
			(layer "F.Fab")
			(hide yes)
			(effects
				(font
					(size 1 1)
					(thickness 0.15)
				)
			)
		)
		(property "MPN" "GRM158R60J226ME01D"
			(at 40.718 212.122 0)
			(layer "F.Fab")
			(hide yes)
			(effects
				(font
					(size 1 1)
					(thickness 0.15)
				)
			)
		)
		(property "Manufacturer" "Murata"
			(at 40.718 212.122 0)
			(layer "F.Fab")
			(hide yes)
			(effects
				(font
					(size 1 1)
					(thickness 0.15)
				)
			)
		)
		(property "Val" "22u"
			(at 40.718 212.122 0)
			(layer "F.Fab")
			(hide yes)
			(effects
				(font
					(size 1 1)
					(thickness 0.15)
				)
			)
		)
		(property "Voltage" ""
			(at 40.718 212.122 0)
			(layer "F.Fab")
			(hide yes)
			(effects
				(font
					(size 1 1)
					(thickness 0.15)
				)
			)
		)
		(sheetname "/Power/")
		(sheetfile "power.kicad_sch")
		(attr smd)
		(fp_rect
			(start -0.925 -0.47)
			(end 0.925 0.47)
			(stroke
				(width 0.05)
				(type default)
			)
			(fill no)
			(layer "F.CrtYd")
		)
		(fp_line
			(start -0.494 0.248)
			(end -0.494 -0.25)
			(stroke
				(width 0.15)
				(type solid)
			)
			(layer "F.Fab")
		)
		(fp_line
			(start 0.504 0.248)
			(end -0.494 0.248)
			(stroke
				(width 0.15)
				(type solid)
			)
			(layer "F.Fab")
		)
		(fp_line
			(start -0.494 -0.25)
			(end 0.504 -0.25)
			(stroke
				(width 0.15)
				(type solid)
			)
			(layer "F.Fab")
		)
		(fp_line
			(start 0.504 -0.25)
			(end 0.504 0.248)
			(stroke
				(width 0.15)
				(type solid)
			)
			(layer "F.Fab")
		)
		(pad "1" smd roundrect
			(at -0.48 0 270)
			(size 0.59 0.64)
			(layers "F.Cu" "F.Mask" "F.Paste")
			(roundrect_rratio 0.25)
			(net 1 "GND")
			(pintype "passive")
		)
		(pad "2" smd roundrect
			(at 0.48 0 270)
			(size 0.59 0.64)
			(layers "F.Cu" "F.Mask" "F.Paste")
			(roundrect_rratio 0.25)
			(net 11 "/Power/OUT_1V2")
			(pintype "passive")
		)
	)
)
